(kicad_pcb
	(version 20241229)
	(generator "pcbnew")
	(generator_version "9.0")
	(general
		(thickness 1.63)
		(legacy_teardrops no)
	)
	(paper "A4")
	(title_block
		(title "CM4 Baseboard")
		(date "2026-01-05")
		(rev "1.1.1")
		(company "Antmicro Ltd")
		(comment 1 "www.antmicro.com")
		(comment 9 "footprints 308-312 of 506")
	)
	(layers
		(0 "F.Cu" signal)
		(4 "In1.Cu" power)
		(6 "In2.Cu" power)
		(8 "In3.Cu" signal)
		(10 "In4.Cu" signal)
		(2 "B.Cu" signal)
		(9 "F.Adhes" user "F.Adhesive")
		(11 "B.Adhes" user "B.Adhesive")
		(13 "F.Paste" user)
		(15 "B.Paste" user)
		(5 "F.SilkS" user "F.Silkscreen")
		(7 "B.SilkS" user "B.Silkscreen")
		(1 "F.Mask" user)
		(3 "B.Mask" user)
		(17 "Dwgs.User" user "User.Drawings")
		(19 "Cmts.User" user "User.Comments")
		(21 "Eco1.User" user "User.Eco1")
		(23 "Eco2.User" user "User.Eco2")
		(25 "Edge.Cuts" user)
		(27 "Margin" user)
		(31 "F.CrtYd" user "F.Courtyard")
		(29 "B.CrtYd" user "B.Courtyard")
		(35 "F.Fab" user)
		(33 "B.Fab" user)
	)
	(footprint "antmicro-footprints:R_0402_1005Metric"
		(layer "F.Cu")
		(at 54.827962 131.8265)
		(descr "Resistor SMD 0402")
		(tags "resistor SMD 0402")
		(property "Reference" "R409"
			(at -1.745 -5.41 0)
			(layer "F.SilkS")
			(effects
				(font
					(size 0.7 0.7)
					(thickness 0.15)
				)
				(justify left bottom)
			)
		)
		(property "Value" "R_10k_0402"
			(at -1.011843 1.772047 0)
			(layer "F.Fab")
			(effects
				(font
					(size 0.7 0.7)
					(thickness 0.15)
				)
				(justify left bottom)
			)
		)
		(property "Datasheet" "https://www.bourns.com/docs/product-datasheets/cr.pdf"
			(at 0 0 0)
			(layer "F.Fab")
			(hide yes)
			(effects
				(font
					(size 1.27 1.27)
					(thickness 0.15)
				)
			)
		)
		(property "Manufacturer" "Bourns"
			(at 0 0 0)
			(unlocked yes)
			(layer "F.Fab")
			(hide yes)
			(effects
				(font
					(size 1 1)
					(thickness 0.15)
				)
			)
		)
		(property "MPN" "CR0402-FX-1002GLF"
			(at 0 0 0)
			(unlocked yes)
			(layer "F.Fab")
			(hide yes)
			(effects
				(font
					(size 1 1)
					(thickness 0.15)
				)
			)
		)
		(property "Val" "10k"
			(at 0 0 0)
			(unlocked yes)
			(layer "F.Fab")
			(hide yes)
			(effects
				(font
					(size 1 1)
					(thickness 0.15)
				)
			)
		)
		(property "License" "Apache-2.0"
			(at 0 0 0)
			(unlocked yes)
			(layer "F.Fab")
			(hide yes)
			(effects
				(font
					(size 1 1)
					(thickness 0.15)
				)
			)
		)
		(property "Author" "Antmicro"
			(at 0 0 0)
			(unlocked yes)
			(layer "F.Fab")
			(hide yes)
			(effects
				(font
					(size 1 1)
					(thickness 0.15)
				)
			)
		)
		(property "Tolerance" "1%"
			(at 0 0 0)
			(unlocked yes)
			(layer "F.Fab")
			(hide yes)
			(effects
				(font
					(size 1 1)
					(thickness 0.15)
				)
			)
		)
		(sheetname "/Ethernet/")
		(sheetfile "ethernet.kicad_sch")
		(attr smd exclude_from_pos_files exclude_from_bom dnp)
		(fp_rect
			(start -0.925 -0.47)
			(end 0.925 0.47)
			(stroke
				(width 0.05)
				(type default)
			)
			(fill no)
			(layer "F.CrtYd")
		)
		(fp_rect
			(start -0.5 -0.25)
			(end 0.5 0.25)
			(stroke
				(width 0.15)
				(type solid)
			)
			(fill no)
			(layer "F.Fab")
		)
		(fp_text user "${REFERENCE}"
			(at -0.95 3.168 0)
			(layer "F.Fab")
			(effects
				(font
					(size 0.7 0.7)
					(thickness 0.15)
				)
				(justify left bottom)
			)
		)
		(fp_text user "Author: Antmicro"
			(at -0.95 4.169 0)
			(layer "F.Fab")
			(effects
				(font
					(size 0.7 0.7)
					(thickness 0.15)
				)
				(justify left bottom)
			)
		)
		(fp_text user "License: Apache-2.0"
			(at -0.95 5.169 0)
			(layer "F.Fab")
			(effects
				(font
					(size 0.7 0.7)
					(thickness 0.15)
				)
				(justify left bottom)
			)
		)
		(pad "1" smd roundrect
			(at -0.48 0)
			(size 0.59 0.64)
			(layers "F.Cu" "F.Mask" "F.Paste")
			(roundrect_rratio 0.25)
			(net 364 "/Ethernet/TPL")
			(pintype "passive")
		)
		(pad "2" smd roundrect
			(at 0.48 0)
			(size 0.59 0.64)
			(layers "F.Cu" "F.Mask" "F.Paste")
			(roundrect_rratio 0.25)
			(net 33 "/Ethernet/VDD")
			(pintype "passive")
		)
	)
	(footprint "antmicro-footprints:C_0402_1005Metric"
		(layer "F.Cu")
		(at 135.137962 159.5665 90)
		(descr "Capacitor SMD 0402")
		(tags "capacitor SMD 0402")
		(property "Reference" "C602"
			(at -8.02 1.63 90)
			(layer "F.SilkS")
			(effects
				(font
					(size 0.7 0.7)
					(thickness 0.15)
				)
				(justify left bottom)
			)
		)
		(property "Value" "C_100n_0402"
			(at -1.022927 2.155213 90)
			(layer "F.Fab")
			(effects
				(font
					(size 0.7 0.7)
					(thickness 0.15)
				)
				(justify left bottom)
			)
		)
		(property "Datasheet" "https://www.murata.com/products/productdetail?partno=GRM155R61H104KE14%23"
			(at 0 0 90)
			(layer "F.Fab")
			(hide yes)
			(effects
				(font
					(size 1.27 1.27)
					(thickness 0.15)
				)
			)
		)
		(property "Manufacturer" "Murata"
			(at 0 0 90)
			(unlocked yes)
			(layer "F.Fab")
			(hide yes)
			(effects
				(font
					(size 1 1)
					(thickness 0.15)
				)
			)
		)
		(property "MPN" "GRM155R61H104KE14D"
			(at 0 0 90)
			(unlocked yes)
			(layer "F.Fab")
			(hide yes)
			(effects
				(font
					(size 1 1)
					(thickness 0.15)
				)
			)
		)
		(property "Val" "100n"
			(at 0 0 90)
			(unlocked yes)
			(layer "F.Fab")
			(hide yes)
			(effects
				(font
					(size 1 1)
					(thickness 0.15)
				)
			)
		)
		(property "License" "Apache-2.0"
			(at 0 0 90)
			(unlocked yes)
			(layer "F.Fab")
			(hide yes)
			(effects
				(font
					(size 1 1)
					(thickness 0.15)
				)
			)
		)
		(property "Author" "Antmicro"
			(at 0 0 90)
			(unlocked yes)
			(layer "F.Fab")
			(hide yes)
			(effects
				(font
					(size 1 1)
					(thickness 0.15)
				)
			)
		)
		(property "Voltage" "50V"
			(at 0 0 90)
			(unlocked yes)
			(layer "F.Fab")
			(hide yes)
			(effects
				(font
					(size 1 1)
					(thickness 0.15)
				)
			)
		)
		(property "Dielectric" "X5R"
			(at 0 0 90)
			(unlocked yes)
			(layer "F.Fab")
			(hide yes)
			(effects
				(font
					(size 1 1)
					(thickness 0.15)
				)
			)
		)
		(sheetname "/CSI/")
		(sheetfile "csi.kicad_sch")
		(attr smd)
		(fp_rect
			(start -0.925 -0.47)
			(end 0.925 0.47)
			(stroke
				(width 0.05)
				(type default)
			)
			(fill no)
			(layer "F.CrtYd")
		)
		(fp_line
			(start 0.504 -0.25)
			(end 0.504 0.248)
			(stroke
				(width 0.15)
				(type solid)
			)
			(layer "F.Fab")
		)
		(fp_line
			(start -0.494 -0.25)
			(end 0.504 -0.25)
			(stroke
				(width 0.15)
				(type solid)
			)
			(layer "F.Fab")
		)
		(fp_line
			(start 0.504 0.248)
			(end -0.494 0.248)
			(stroke
				(width 0.15)
				(type solid)
			)
			(layer "F.Fab")
		)
		(fp_line
			(start -0.494 0.248)
			(end -0.494 -0.25)
			(stroke
				(width 0.15)
				(type solid)
			)
			(layer "F.Fab")
		)
		(fp_text user "Author: Antmicro"
			(at -0.939 3.399 90)
			(layer "F.Fab")
			(effects
				(font
					(size 0.7 0.7)
					(thickness 0.15)
				)
				(justify left bottom)
			)
		)
		(fp_text user "License: Apache-2.0"
			(at -0.939 5.799 90)
			(layer "F.Fab")
			(effects
				(font
					(size 0.7 0.7)
					(thickness 0.15)
				)
				(justify left bottom)
			)
		)
		(fp_text user "${REFERENCE}"
			(at -0.939 4.599 90)
			(layer "F.Fab")
			(effects
				(font
					(size 0.7 0.7)
					(thickness 0.15)
				)
				(justify left bottom)
			)
		)
		(pad "1" smd roundrect
			(at -0.48 0 90)
			(size 0.59 0.64)
			(layers "F.Cu" "F.Mask" "F.Paste")
			(roundrect_rratio 0.25)
			(net 9 "+3V3")
			(pintype "passive")
		)
		(pad "2" smd roundrect
			(at 0.48 0 90)
			(size 0.59 0.64)
			(layers "F.Cu" "F.Mask" "F.Paste")
			(roundrect_rratio 0.25)
			(net 3 "GND")
			(pintype "passive")
		)
	)
	(footprint "antmicro-footprints:R_0402_1005Metric"
		(layer "F.Cu")
		(at 76.692962 155.7415 90)
		(descr "Resistor SMD 0402")
		(tags "resistor SMD 0402")
		(property "Reference" "R258"
			(at -3.125 1.25 90)
			(layer "F.SilkS")
			(effects
				(font
					(size 0.7 0.7)
					(thickness 0.15)
				)
				(justify left bottom)
			)
		)
		(property "Value" "R_0R_0402"
			(at -1.011843 1.772047 90)
			(layer "F.Fab")
			(effects
				(font
					(size 0.7 0.7)
					(thickness 0.15)
				)
				(justify left bottom)
			)
		)
		(property "Datasheet" "https://industrial.panasonic.com/cdbs/www-data/pdf/RDA0000/AOA0000C301.pdf"
			(at 0 0 90)
			(layer "F.Fab")
			(hide yes)
			(effects
				(font
					(size 1.27 1.27)
					(thickness 0.15)
				)
			)
		)
		(property "Manufacturer" "Panasonic"
			(at 0 0 90)
			(unlocked yes)
			(layer "F.Fab")
			(hide yes)
			(effects
				(font
					(size 1 1)
					(thickness 0.15)
				)
			)
		)
		(property "MPN" "ERJ2GE0R00X"
			(at 0 0 90)
			(unlocked yes)
			(layer "F.Fab")
			(hide yes)
			(effects
				(font
					(size 1 1)
					(thickness 0.15)
				)
			)
		)
		(property "Val" "0R"
			(at 0 0 90)
			(unlocked yes)
			(layer "F.Fab")
			(hide yes)
			(effects
				(font
					(size 1 1)
					(thickness 0.15)
				)
			)
		)
		(property "License" "Apache-2.0"
			(at 0 0 90)
			(unlocked yes)
			(layer "F.Fab")
			(hide yes)
			(effects
				(font
					(size 1 1)
					(thickness 0.15)
				)
			)
		)
		(property "Author" "Antmicro"
			(at 0 0 90)
			(unlocked yes)
			(layer "F.Fab")
			(hide yes)
			(effects
				(font
					(size 1 1)
					(thickness 0.15)
				)
			)
		)
		(property "Tolerance" "~"
			(at 0 0 90)
			(unlocked yes)
			(layer "F.Fab")
			(hide yes)
			(effects
				(font
					(size 1 1)
					(thickness 0.15)
				)
			)
		)
		(property "Current" "1A"
			(at 0 0 90)
			(unlocked yes)
			(layer "F.Fab")
			(hide yes)
			(effects
				(font
					(size 1 1)
					(thickness 0.15)
				)
			)
		)
		(sheetname "/Compute module/")
		(sheetfile "compute-module.kicad_sch")
		(attr smd)
		(fp_rect
			(start -0.925 -0.47)
			(end 0.925 0.47)
			(stroke
				(width 0.05)
				(type default)
			)
			(fill no)
			(layer "F.CrtYd")
		)
		(fp_rect
			(start -0.5 -0.25)
			(end 0.5 0.25)
			(stroke
				(width 0.15)
				(type solid)
			)
			(fill no)
			(layer "F.Fab")
		)
		(fp_text user "${REFERENCE}"
			(at -0.95 3.168 90)
			(layer "F.Fab")
			(effects
				(font
					(size 0.7 0.7)
					(thickness 0.15)
				)
				(justify left bottom)
			)
		)
		(fp_text user "License: Apache-2.0"
			(at -0.95 5.169 90)
			(layer "F.Fab")
			(effects
				(font
					(size 0.7 0.7)
					(thickness 0.15)
				)
				(justify left bottom)
			)
		)
		(fp_text user "Author: Antmicro"
			(at -0.95 4.169 90)
			(layer "F.Fab")
			(effects
				(font
					(size 0.7 0.7)
					(thickness 0.15)
				)
				(justify left bottom)
			)
		)
		(pad "1" smd roundrect
			(at -0.48 0 90)
			(size 0.59 0.64)
			(layers "F.Cu" "F.Mask" "F.Paste")
			(roundrect_rratio 0.25)
			(net 124 "/Compute module/DSICtrl.DIM")
			(pintype "passive")
		)
		(pad "2" smd roundrect
			(at 0.48 0 90)
			(size 0.59 0.64)
			(layers "F.Cu" "F.Mask" "F.Paste")
			(roundrect_rratio 0.25)
			(net 237 "/Compute module/GPIO.18")
			(pintype "passive")
		)
	)
	(footprint "antmicro-footprints:C_0402_1005Metric"
		(layer "F.Cu")
		(at 95.117962 135.707236 90)
		(descr "Capacitor SMD 0402")
		(tags "capacitor SMD 0402")
		(property "Reference" "C918"
			(at -2.639264 1.3 90)
			(layer "F.SilkS")
			(effects
				(font
					(size 0.7 0.7)
					(thickness 0.15)
				)
				(justify left bottom)
			)
		)
		(property "Value" "C_100n_0402"
			(at -1.022927 2.155213 90)
			(layer "F.Fab")
			(effects
				(font
					(size 0.7 0.7)
					(thickness 0.15)
				)
				(justify left bottom)
			)
		)
		(property "Datasheet" "https://www.murata.com/products/productdetail?partno=GRM155R61H104KE14%23"
			(at 0 0 90)
			(layer "F.Fab")
			(hide yes)
			(effects
				(font
					(size 1.27 1.27)
					(thickness 0.15)
				)
			)
		)
		(property "Manufacturer" "Murata"
			(at 0 0 90)
			(unlocked yes)
			(layer "F.Fab")
			(hide yes)
			(effects
				(font
					(size 1 1)
					(thickness 0.15)
				)
			)
		)
		(property "MPN" "GRM155R61H104KE14D"
			(at 0 0 90)
			(unlocked yes)
			(layer "F.Fab")
			(hide yes)
			(effects
				(font
					(size 1 1)
					(thickness 0.15)
				)
			)
		)
		(property "Val" "100n"
			(at 0 0 90)
			(unlocked yes)
			(layer "F.Fab")
			(hide yes)
			(effects
				(font
					(size 1 1)
					(thickness 0.15)
				)
			)
		)
		(property "License" "Apache-2.0"
			(at 0 0 90)
			(unlocked yes)
			(layer "F.Fab")
			(hide yes)
			(effects
				(font
					(size 1 1)
					(thickness 0.15)
				)
			)
		)
		(property "Author" "Antmicro"
			(at 0 0 90)
			(unlocked yes)
			(layer "F.Fab")
			(hide yes)
			(effects
				(font
					(size 1 1)
					(thickness 0.15)
				)
			)
		)
		(property "Voltage" "50V"
			(at 0 0 90)
			(unlocked yes)
			(layer "F.Fab")
			(hide yes)
			(effects
				(font
					(size 1 1)
					(thickness 0.15)
				)
			)
		)
		(property "Dielectric" "X5R"
			(at 0 0 90)
			(unlocked yes)
			(layer "F.Fab")
			(hide yes)
			(effects
				(font
					(size 1 1)
					(thickness 0.15)
				)
			)
		)
		(sheetname "/USB/")
		(sheetfile "usb.kicad_sch")
		(attr smd)
		(fp_rect
			(start -0.925 -0.47)
			(end 0.925 0.47)
			(stroke
				(width 0.05)
				(type default)
			)
			(fill no)
			(layer "F.CrtYd")
		)
		(fp_line
			(start 0.504 -0.25)
			(end 0.504 0.248)
			(stroke
				(width 0.15)
				(type solid)
			)
			(layer "F.Fab")
		)
		(fp_line
			(start -0.494 -0.25)
			(end 0.504 -0.25)
			(stroke
				(width 0.15)
				(type solid)
			)
			(layer "F.Fab")
		)
		(fp_line
			(start 0.504 0.248)
			(end -0.494 0.248)
			(stroke
				(width 0.15)
				(type solid)
			)
			(layer "F.Fab")
		)
		(fp_line
			(start -0.494 0.248)
			(end -0.494 -0.25)
			(stroke
				(width 0.15)
				(type solid)
			)
			(layer "F.Fab")
		)
		(fp_text user "Author: Antmicro"
			(at -0.939 3.399 90)
			(layer "F.Fab")
			(effects
				(font
					(size 0.7 0.7)
					(thickness 0.15)
				)
				(justify left bottom)
			)
		)
		(fp_text user "${REFERENCE}"
			(at -0.939 4.599 90)
			(layer "F.Fab")
			(effects
				(font
					(size 0.7 0.7)
					(thickness 0.15)
				)
				(justify left bottom)
			)
		)
		(fp_text user "License: Apache-2.0"
			(at -0.939 5.799 90)
			(layer "F.Fab")
			(effects
				(font
					(size 0.7 0.7)
					(thickness 0.15)
				)
				(justify left bottom)
			)
		)
		(pad "1" smd roundrect
			(at -0.48 0 90)
			(size 0.59 0.64)
			(layers "F.Cu" "F.Mask" "F.Paste")
			(roundrect_rratio 0.25)
			(net 27 "/USB/USB_3V3")
			(pintype "passive")
		)
		(pad "2" smd roundrect
			(at 0.48 0 90)
			(size 0.59 0.64)
			(layers "F.Cu" "F.Mask" "F.Paste")
			(roundrect_rratio 0.25)
			(net 3 "GND")
			(pintype "passive")
		)
	)
	(footprint "antmicro-footprints:C_0805_2012Metric"
		(layer "F.Cu")
		(at 50.917962 127.4365)
		(descr "Capacitor SMD 0805")
		(tags "capacitor SMD 0805")
		(property "Reference" "C401"
			(at -4.6 0.72 0)
			(layer "F.SilkS")
			(effects
				(font
					(size 0.7 0.7)
					(thickness 0.15)
				)
				(justify left bottom)
			)
		)
		(property "Value" "C_100n_100V_0805"
			(at -2.055717 1.963152 0)
			(layer "F.Fab")
			(effects
				(font
					(size 0.7 0.7)
					(thickness 0.15)
				)
				(justify left bottom)
			)
		)
		(property "Datasheet" "https://product.samsungsem.com/mlcc/CL21B104KCFNNN.do"
			(at 0 0 0)
			(layer "F.Fab")
			(hide yes)
			(effects
				(font
					(size 1.27 1.27)
					(thickness 0.15)
				)
			)
		)
		(property "Manufacturer" "Samsung Electro-Mechanics"
			(at 0 0 0)
			(unlocked yes)
			(layer "F.Fab")
			(hide yes)
			(effects
				(font
					(size 1 1)
					(thickness 0.15)
				)
			)
		)
		(property "MPN" "CL21B104KCFNNNE"
			(at 0 0 0)
			(unlocked yes)
			(layer "F.Fab")
			(hide yes)
			(effects
				(font
					(size 1 1)
					(thickness 0.15)
				)
			)
		)
		(property "Val" "100n"
			(at 0 0 0)
			(unlocked yes)
			(layer "F.Fab")
			(hide yes)
			(effects
				(font
					(size 1 1)
					(thickness 0.15)
				)
			)
		)
		(property "License" "Apache-2.0"
			(at 0 0 0)
			(unlocked yes)
			(layer "F.Fab")
			(hide yes)
			(effects
				(font
					(size 1 1)
					(thickness 0.15)
				)
			)
		)
		(property "Author" "Antmicro"
			(at 0 0 0)
			(unlocked yes)
			(layer "F.Fab")
			(hide yes)
			(effects
				(font
					(size 1 1)
					(thickness 0.15)
				)
			)
		)
		(property "Voltage" "100V"
			(at 0 0 0)
			(unlocked yes)
			(layer "F.Fab")
			(hide yes)
			(effects
				(font
					(size 1 1)
					(thickness 0.15)
				)
			)
		)
		(property "Dielectric" "X7R"
			(at 0 0 0)
			(unlocked yes)
			(layer "F.Fab")
			(hide yes)
			(effects
				(font
					(size 1 1)
					(thickness 0.15)
				)
			)
		)
		(property "Public" "False"
			(at 0 0 0)
			(unlocked yes)
			(layer "F.Fab")
			(hide yes)
			(effects
				(font
					(size 1 1)
					(thickness 0.15)
				)
			)
		)
		(sheetname "/Ethernet/")
		(sheetfile "ethernet.kicad_sch")
		(attr smd)
		(fp_line
			(start -0.3 -0.7)
			(end 0.3 -0.7)
			(stroke
				(width 0.15)
				(type solid)
			)
			(layer "F.SilkS")
		)
		(fp_line
			(start -0.3 0.7)
			(end 0.3 0.7)
			(stroke
				(width 0.15)
				(type solid)
			)
			(layer "F.SilkS")
		)
		(fp_rect
			(start 1.95 -0.9)
			(end -1.95 0.9)
			(stroke
				(width 0.05)
				(type default)
			)
			(fill no)
			(layer "F.CrtYd")
		)
		(fp_rect
			(start -0.95 -0.675)
			(end 0.95 0.675)
			(stroke
				(width 0.15)
				(type solid)
			)
			(fill no)
			(layer "F.Fab")
		)
		(fp_text user "Author: Antmicro"
			(at -1.9 5.947 0)
			(layer "F.Fab")
			(effects
				(font
					(size 0.7 0.7)
					(thickness 0.15)
				)
				(justify left bottom)
			)
		)
		(fp_text user "${REFERENCE}"
			(at -1.9 3.947 0)
			(layer "F.Fab")
			(effects
				(font
					(size 0.7 0.7)
					(thickness 0.15)
				)
				(justify left bottom)
			)
		)
		(fp_text user "License: Apache-2.0"
			(at -1.9 4.947 0)
			(layer "F.Fab")
			(effects
				(font
					(size 0.7 0.7)
					(thickness 0.15)
				)
				(justify left bottom)
			)
		)
		(pad "1" smd roundrect
			(at -1.1 0)
			(size 1.2 1.3)
			(layers "F.Cu" "F.Mask" "F.Paste")
			(roundrect_rratio 0.25)
			(net 90 "/Ethernet/VSS")
			(pintype "passive")
		)
		(pad "2" smd roundrect
			(at 1.1 0)
			(size 1.2 1.3)
			(layers "F.Cu" "F.Mask" "F.Paste")
			(roundrect_rratio 0.25)
			(net 33 "/Ethernet/VDD")
			(pintype "passive")
		)
	)
)
